FILE_TYPE = CONNECTIVITY;
{Allegro Design Entry HDL 17.2-2016 S081 (4005846) 1/11/2022}
"PAGE_NUMBER" = 156;
0"NC";
1"GND\g";
2"GND\g";
3"P3V3_STBY\g";
4"GND\g";
5"GND\g";
6"GND\g";
7"P3V_BAT";
8"GND\g";
9"CLR_CMOS";
10"P3V_BAT_R";
11"CLR_CMOS_N";
12"BAT_LDO_EN";
13"P3V3_RTC_AUX\g";
14"GND\g";
15"P1V5_BAT\g";
16"P1V5_BAT_OUT"CDS_PHYS_NET_NAME"P1V5_BAT_OUT";
17"GND\g";
18"GND\g";
%"CONN3_G800LQ305005FTHR"
"1","(-1500,7575)","6","pure_quanta","I1";
;
LOCATION"JP12"
$SEC"1"
CDS_SEC"1"
PART_TYPE"THLF"
MATERIAL"IO"
VALUE"CONN3_G800LQ305005FTHR"
PART_NUMBER"DFHD03MS403"
NEEDS_NO_SIZE"TRUE"
CDS_LIB"pure_quanta"
CDS_LMAN_SYM_OUTLINE"-50,100,50,-100";
"3"
$PN"3"1;
"2"
$PN"2"15;
"1"
$PN"1"16;
%"Q_RES"
"1","(-2875,5675)","0","pure_quanta","I10";
;
LOCATION"R1779"
$SEC"1"
CDS_SEC"1"
WATTAGE"1/16W"
MATERIAL"CHIP"
TOLERANCE"1%"
VALUE"100"
PART_NUMBER"TMP_QCS11002FB22"
PACK_TYPE"0402LF"
CDS_LIB"pure_quanta";
"B"
$PN"2"15;
"A"
$PN"1"11;
%"UNIVERSAL_GND"
"1","(-1800,7300)","2","pure_quanta_power","I2";
;
CDS_LIB"pure_quanta_power"
HDL_POWER"GND";
"A"1;
%"NCP698SQ15T1G"
"1","(-4200,6900)","0","pure_quanta","I22";
;
LOCATION"U167"
$SEC"1"
CDS_SEC"1"
PART_TYPE"SMLF"
MATERIAL"IC"
VALUE"NCP698SQ15T1G"
PART_NUMBER"AL000698000"
CDS_LIB"pure_quanta"
CDS_LMAN_SYM_OUTLINE"-200,125,200,-125"
NEEDS_NO_SIZE"TRUE";
"EN"
$PN"4"12;
"VIN"
$PN"2"13;
"VOUT"
$PN"3"16;
"GND"
$PN"1"2;
%"UNIVERSAL_GND"
"1","(-4575,6575)","0","pure_quanta_power","I23";
;
CDS_LIB"pure_quanta_power"
HDL_POWER"GND";
"A"2;
%"Q_RES"
"2","(-4725,6325)","0","pure_quanta","I24";
;
LOCATION"R1777"
$SEC"1"
CDS_SEC"1"
WATTAGE"1/16W"
MATERIAL"CHIP"
TOLERANCE"1%"
VALUE"1K"
PART_NUMBER"TMP_QCS21002FB24"
PACK_TYPE"0402LF"
CDS_LIB"pure_quanta";
"A"
$PN"1"13;
"B"
$PN"2"12;
%"UNIVERSAL_POWER"
"1","(-5850,7425)","0","pure_quanta_power","I25";
;
HDL_POWER"P3V3_RTC_AUX"
CDS_LIB"pure_quanta_power";
"A"13;
%"Q_CAP"
"1","(-5600,6775)","2","pure_quanta","I26";
;
LOCATION"C193"
$SEC"1"
CDS_SEC"1"
MATERIAL"X7R"
TOLERANCE"10%"
VALUE"100NF"
PART_NUMBER"CH4106K1B01"
VOLTAGE"50V"
PACK_TYPE"C0402"
CDS_LIB"pure_quanta"
ROOM"MIO_LEGACY";
"B"
$PN"2"14;
"A"
$PN"1"13;
%"Q_CAP"
"1","(-6050,6775)","0","pure_quanta","I27";
;
LOCATION"C45"
$SEC"1"
CDS_SEC"1"
MATERIAL"X6S"
TOLERANCE"10%"
VALUE"1UF"
PART_NUMBER"CH5104KEB02"
VOLTAGE"25V"
PACK_TYPE"C0402"
CDS_LIB"pure_quanta";
"B"
$PN"2"14;
"A"
$PN"1"13;
%"UNIVERSAL_GND"
"1","(-6050,6250)","0","pure_quanta_power","I28";
;
CDS_LIB"pure_quanta_power"
HDL_POWER"GND";
"A"14;
%"UNIVERSAL_POWER"
"1","(-7500,7500)","0","pure_quanta_power","I29";
;
HDL_POWER"P3V3_STBY"
CDS_LIB"pure_quanta_power";
"A"3;
%"UNIVERSAL_POWER"
"1","(-2200,6775)","0","pure_quanta_power","I3";
;
HDL_POWER"P1V5_BAT"
CDS_LIB"pure_quanta_power";
"A"15;
%"SCHOTTKY_DUAL_12A_3C"
"1","(-7100,6975)","5","pure_quanta","I30";
;
LOCATION"U166"
$SEC"1"
CDS_SEC"1"
PART_TYPE"SMLF"
MATERIAL"IC"
VALUE"BAT54CW"
PART_NUMBER"BCBAT54CZ13"
CDS_LIB"pure_quanta"
NEEDS_NO_SIZE"TRUE"
CDS_LMAN_SYM_OUTLINE"-100,50,100,-50";
"C"
$PN"3"13;
"B"
$PN"1"3;
"A"
$PN"2"10;
%"Q_RES"
"1","(-8075,6925)","0","pure_quanta","I32";
;
LOCATION"R1775"
$SEC"1"
CDS_SEC"1"
WATTAGE"1/16W"
MATERIAL"CHIP"
TOLERANCE"1%"
VALUE"1K"
PART_NUMBER"TMP_QCS21002FB24"
PACK_TYPE"0402LF"
CDS_LIB"pure_quanta";
"B"
$PN"2"10;
"A"
$PN"1"7;
%"Q_CAP"
"1","(-6150,4800)","0","pure_quanta","I35";
;
LOCATION"C1563"
$SEC"1"
CDS_SEC"1"
MATERIAL"X7R"
TOLERANCE"10%"
VALUE"0.1UF"
PART_NUMBER"CH4103K1B08"
VOLTAGE"16V"
PACK_TYPE"C0402"
CDS_LIB"pure_quanta";
"B"
$PN"2"8;
"A"
$PN"1"9;
%"UNIVERSAL_GND"
"1","(-6150,4325)","0","pure_quanta_power","I36";
;
CDS_LIB"pure_quanta_power"
HDL_POWER"GND";
"A"8;
%"Q_RES"
"2","(-6600,4800)","0","pure_quanta","I37";
;
LOCATION"R1776"
$SEC"1"
CDS_SEC"1"
WATTAGE"1/16W"
MATERIAL"CHIP"
TOLERANCE"1%"
VALUE"1K"
PART_NUMBER"TMP_QCS21002FB24"
PACK_TYPE"0402LF"
BOM_COST"VR_SYSTEM "
CDS_LIB"pure_quanta";
"A"
$PN"1"9;
"B"
$PN"2"8;
%"CONN2_AAABAT029P15"
"1","(-9025,6925)","2","pure_quanta","I39";
;
LOCATION"BT2"
$SEC"1"
CDS_SEC"1"
PART_TYPE"THLF"
MATERIAL"IO"
VALUE"CONN2_AAA-BAT-029-P15"
PART_NUMBER"DFHS02FR031"
CDS_LMAN_SYM_OUTLINE"-50,50,50,-50"
NEEDS_NO_SIZE"TRUE"
CDS_LIB"pure_quanta";
"2"
$PN"2"4;
"1"
$PN"1"7;
%"Q_CAP"
"1","(-1975,6250)","0","pure_quanta","I4";
;
LOCATION"C1567"
$SEC"1"
CDS_SEC"1"
MATERIAL"X6S"
TOLERANCE"10%"
VALUE"1UF"
PART_NUMBER"CH5104KEB02"
VOLTAGE"25V"
PACK_TYPE"C0402"
CDS_LIB"pure_quanta";
"B"
$PN"2"5;
"A"
$PN"1"15;
%"GND"
"1","(-9300,6425)","0","pure_quanta_power","I40";
;
SIZE"1B"
CDS_LIB"pure_quanta_power"
HDL_POWER"GND";
"A<SIZE-1..0>\NAC"4;
%"MOSFET_DUAL_6P"
"1","(-5200,5000)","0","pure_quanta","I41";
;
LOCATION"Q8"
$SEC"1"
CDS_SEC"1"
PART_TYPE"SMLF"
MATERIAL"IC"
VALUE"2N7002KDW"
PART_NUMBER"BAM70020047"
CDS_LMAN_SYM_OUTLINE"-150,100,150,-100"
NEEDS_NO_SIZE"TRUE"
CDS_LIB"pure_quanta";
"D2"
$PN"3"12;
"D1"
$PN"6"11;
"S2"
$PN"4"18;
"S1"
$PN"1"17;
"G2"
$PN"5"9;
"G1"
$PN"2"9;
%"UNIVERSAL_GND"
"1","(-4850,5050)","1","pure_quanta_power","I42";
;
CDS_LIB"pure_quanta_power"
HDL_POWER"GND";
"A"18;
%"UNIVERSAL_GND"
"1","(-5550,5050)","5","pure_quanta_power","I43";
;
CDS_LIB"pure_quanta_power"
HDL_POWER"GND";
"A"17;
%"TP"
"1","(-1250,7550)","0","pure_quanta","I45";
;
LOCATION"JP12_12"
$SEC"1"
CDS_SEC"1"
MATERIAL"EMPTY"
CDS_LIB"pure_quanta"
PART_NUMBER"TP26"
PACK_TYPE"TP";
"TP \B"
$PN"1"
$PIN_NUMBER"?"0;
%"TP"
"1","(-9050,7525)","0","pure_quanta","I46";
;
LOCATION"BATTERY_BT2"
$SEC"1"
CDS_SEC"1"
MATERIAL"EMPTY"
CDS_LIB"pure_quanta"
PART_NUMBER"TP26"
PACK_TYPE"TP";
"TP \B"
$PN"1"
$PIN_NUMBER"?"0;
%"UNIVERSAL_GND"
"1","(-1975,5900)","0","pure_quanta_power","I5";
;
CDS_LIB"pure_quanta_power"
HDL_POWER"GND";
"A"5;
%"Q_CAP"
"1","(-3175,6750)","0","pure_quanta","I6";
;
LOCATION"C1564"
$SEC"1"
CDS_SEC"1"
MATERIAL"X6S"
TOLERANCE"10%"
VALUE"1UF"
PART_NUMBER"CH5104KEB02"
VOLTAGE"25V"
PACK_TYPE"C0402"
CDS_LIB"pure_quanta";
"B"
$PN"2"6;
"A"
$PN"1"16;
%"UNIVERSAL_GND"
"1","(-3175,6375)","0","pure_quanta_power","I7";
;
CDS_LIB"pure_quanta_power"
HDL_POWER"GND";
"A"6;
END.
